# T6G (Grand Teton) — schematic parts with pin connectivity, parts 4516–4572 of 8303; source: Cadence DE-HDL packaged netlist (pstxprt.dat, pstxnet.dat, pstchip.dat)

PR6625  Q_RES  499 1% CHIP  pkg 0603LF  page 365 : 1 = P0V9_CPU1_RT_2D ; 2 = GND
PR6626  Q_RES  0 5% CHIP  pkg 0402LF  page 365 : 1 = P0V9_RETIMER_CPU1_VOS1 ; 2 = P0V9_CPU1_RT_2D
PR6627  Q_RES  2.2 5% CHIP  pkg 0402LF  page 365 : 1 = P0V9_RETIMER_CPU1_PVCC ; 2 = P0V9_RETIMER_CPU1_VCC2
PR6628  Q_RES  8.87K 1% EMPTY  pkg 0402LF  page 365 : 1 = P0V9_RETIMER_CPU1_LSET2 ; 2 = GND
PR6629  Q_RES  5.6 1% CHIP  pkg 0402LF  page 365 : 1 = SW_P0V9_RETIMER_CPU1_BOOT2 ; 2 = SW_P0V9_RETIMER_CPU1_BOOT2_RC
PR6630  Q_RES  1.5 1% EMPTY  pkg 0402LF  page 365 : 1 = SW_P0V9_RETIMER_CPU1_SW2_RC ; 2 = GND
PR6631  Q_RES  0 5% CHIP  pkg 0402LF  page 365 : 1 = P0V9_RETIMER_CPU1_VOS2 ; 2 = P0V9_CPU1_RT_2D
PR6800  Q_RES  2.2 1% CHIP  pkg 0402LF  page 360 : 1 = SW_P1V8_RETIMER_CPU0_BST ; 2 = SW_P1V8_RETIMER_CPU0_BST_R
PR6801  Q_RES  2.2 1% CHIP  pkg 0402LF  page 361 : 1 = SW_P1V8_RETIMER_CPU1_BST ; 2 = SW_P1V8_RETIMER_CPU1_BST_R
PR6802  Q_RES  0 5% EMPTY  pkg 0402LF  page 364 : 1 = TP_P0V9_RETIMER_CPU1_SVID_ALERT_N ; 2 = GND
PR6803  Q_RES  1K 1% EMPTY  pkg 0402LF  page 362 : 1 = P3V3_AUX ; 2 = P0V9_RETIMER_CPU0_SVID_SDA
PR6804  Q_RES  1K 1% EMPTY  pkg 0402LF  page 364 : 1 = P3V3_AUX ; 2 = P0V9_RETIMER_CPU1_SVID_SDA
PR6805  Q_RES  1K 1% EMPTY  pkg 0402LF  page 362 : 1 = P3V3_AUX ; 2 = P0V9_RETIMER_CPU0_SVID_CLK
PR6806  Q_RES  1K 1% EMPTY  pkg 0402LF  page 364 : 1 = P3V3_AUX ; 2 = P0V9_RETIMER_CPU1_SVID_CLK
PR6807  Q_RES  0 5% EMPTY  pkg 0402LF  page 362 : 1 = P12V_AUX ; 2 = P0V9_RETIMER_CPU0_VMON
PR6808  Q_RES  0 5% EMPTY  pkg 0402LF  page 364 : 1 = P12V_AUX ; 2 = P0V9_RETIMER_CPU1_VMON
PR6809  Q_RES  0 5% CHIP  pkg 0402LF  page 364 : 1 = P12V_AUX ; 2 = P0V9_RETIMER_CPU1_VINSEN
PR6810  Q_RES  0 5% CHIP  pkg 0402LF  page 362 : 1 = P0V9_RETIMER_CPU0_SVID_CLK ; 2 = GND
PR6811  Q_RES  0 5% CHIP  pkg 0402LF  page 364 : 1 = P0V9_RETIMER_CPU1_SVID_CLK ; 2 = GND
PR6812  Q_RES  1K 1% CHIP  pkg 0402LF  page 364 : 1 = P3V3_AUX ; 2 = TP_P0V9_RETIMER_CPU1_VRHOT
PR6813  Q_RES  1K 1% EMPTY  pkg 0402LF  page 364 : 1 = P0V9_RETIMER_CPU1_VINSEN ; 2 = GND
PR6814  Q_RES  10K 1% EMPTY  pkg 0402LF  page 362 : 1 = P0V9_RETIMER_CPU0_TEMP0 ; 2 = GND
PR6815  Q_RES  10K 1% EMPTY  pkg 0402LF  page 364 : 1 = P0V9_RETIMER_CPU1_TEMP0 ; 2 = GND
PR6816  Q_RES  0 5% CHIP  pkg 0402LF  page 364 : 1 = P0V9_RETIMER_CPU1_VRHOT ; 2 = TP_P0V9_RETIMER_CPU1_VRHOT
PR6817  Q_RES  1K 1% EMPTY  pkg 0402LF  page 362 : 1 = P3V3_AUX ; 2 = TP_P0V9_RETIMER_CPU0_SVID_ALERT_N
PR6818  Q_RES  1K 1% EMPTY  pkg 0402LF  page 364 : 1 = P3V3_AUX ; 2 = TP_P0V9_RETIMER_CPU1_SVID_ALERT_N
PR6819  Q_RES  0 5% CHIP  pkg 0402LF  page 362 : 1 = P0V9_RETIMER_CPU0_SVID_SDA ; 2 = GND
PR6820  Q_RES  0 5% CHIP  pkg 0402LF  page 364 : 1 = P0V9_RETIMER_CPU1_SVID_SDA ; 2 = GND
PR6821  Q_RES  0 5% CHIP  pkg 0402LF  page 364 : 1 = P0V9_RETIMER_CPU1_VMON ; 2 = GND
PR8000  Q_RES  0 5% CHIP  pkg 0402LF  page 192 : 1 = SW_PVDD_33_S5_BST ; 2 = SW_PVDD_33_S5_BST_R
PR8001  Q_RES  2.2 1% CHIP  pkg 0402LF  page 209 : 1 = SW_PVDD18_S5_P0_BST ; 2 = SW_PVDD18_S5_P0_BST_R
PR8002  Q_RES  2.2 1% CHIP  pkg 0402LF  page 226 : 1 = SW_PVDD18_S5_P1_BST ; 2 = SW_PVDD18_S5_P1_BST_R
PR8003  Q_RES  2.2 1% CHIP  pkg 0402LF  page 269 : 1 = SW_P1V8_AUX_BT ; 2 = SW_P1V8_AUX_BT_R
PR8004  Q_RES  2.2 1% CHIP  pkg 0402LF  page 270 : 1 = SW_P1V2_AUX_BT ; 2 = SW_P1V2_AUX_BT_R
PR8005  Q_RES  0 5% CHIP  pkg 0402LF  page 193 : 1 = SVID_PVDDCR_CPU0_P0_SVC_R ; 2 = SVID_PVDDCR_CPU0_P0_SVC_R1
PR8006  Q_RES  0 5% CHIP  pkg 0402LF  page 193 : 1 = SVID_PVDDCR_CPU0_P0_SVD_R ; 2 = SVID_PVDDCR_CPU0_P0_SVD_R1
PR8007  Q_RES  0 5% CHIP  pkg 0402LF  page 200 : 1 = SVID_PVDDCR_CPU1_P0_SVC_R ; 2 = SVID_PVDDCR_CPU1_P0_SVC_R1
PR8008  Q_RES  0 5% CHIP  pkg 0402LF  page 200 : 1 = SVID_PVDDCR_CPU1_P0_SVD_R ; 2 = SVID_PVDDCR_CPU1_P0_SVD_R1
PR8009  Q_RES  0 5% CHIP  pkg 0402LF  page 210 : 1 = SVID_PVDDCR_CPU0_P1_SVC_R ; 2 = SVID_PVDDCR_CPU0_P1_SVC_R1
PR8010  Q_RES  0 5% CHIP  pkg 0402LF  page 210 : 1 = SVID_PVDDCR_CPU0_P1_SVD_R ; 2 = SVID_PVDDCR_CPU0_P1_SVD_R1
PR8011  Q_RES  0 5% CHIP  pkg 0402LF  page 217 : 1 = SVID_PVDDCR_CPU1_P1_SVC_R ; 2 = SVID_PVDDCR_CPU1_P1_SVC_R1
PR8012  Q_RES  0 5% CHIP  pkg 0402LF  page 217 : 1 = SVID_PVDDCR_CPU1_P1_SVD_R ; 2 = SVID_PVDDCR_CPU1_P1_SVD_R1
PR8073  Q_RES  1K 1% CHIP  pkg 0402LF  page 190 : 1 = P3V3_AUX ; 2 = PWRGD_P3V3_AUX_R1
PR8089  Q_RES  16.9K 1% CHIP  pkg 0402LF  page 189 : 1 = P5V_AUX_CS ; 2 = GND
PR8091  Q_RES  11.8K 0.1% CHIP  pkg 0402LF  page 189 : 1 = P5V_AUX_FB ; 2 = GND
PR8092  Q_RES  86.6K 1% CHIP  pkg 0402LF  page 189 : 1 = P5V_AUX_FB ; 2 = P5V_AUX
PR8389  Q_RES  1 1% CHIP  pkg 0402LF  page 190 : 1 = P3V3_AUX_VDRV ; 2 = P3V3_AUX_VCC

PU2  ISL99390FRZTR5935  ISL99390FRZ-TR5935 IC  pkg QFN21_6X5XB  page 201
  1  VOS  IN  = PVDDCR_CPU1_P0_VOS2
  2  AGND  POWER  = GND
  3  VCC  POWER  = PVDDCR_CPU1_P0_VCC2
  4  PVCC  POWER  = PVDDCR_CPU1_P0_PVCC
  5  PGND1  POWER  = GND
  6  GL1  OUT  = NC_PVDDCR_CPU1_P0_GL1_2
  7_9-20_24  PGND2  POWER  = GND
  10_19  SW  OUT  = SW_PVDDCR_CPU1_P0_SW2
  25_29  VIN1  IN  = SW_P12V_AUX_PVDDCR_CPU1_P0_FLT
  30  VIN2  IN  = SW_P12V_AUX_PVDDCR_CPU1_P0_FLT
  31  DNC  TRI  = NC_PVDDCR_CPU1_P0_DNC2
  32  PHASE  POWER  = SW_PVDDCR_CPU1_P0_BOOTR2
  33  BOOT  POWER  = SW_PVDDCR_CPU1_P0_BOOT2
  34  PWM  IN  = PVDDCR_CPU1_P0_PWM2
  35  EN  IN  = PVDDCR_CPU1_P0_VCC2
  36  TOUT_FLT  OUT  = PVDDCR_CPU1_P0_TEMP0
  37  LSET  OUT  = PVDDCR_CPU1_P0_LSET2
  38  IOUT  OUT  = PVDDCR_CPU1_P0_IMON2
  39  REFIN  IN  = PVDDCR_CPU1_P0_VCCS
  40  PGND3  POWER  = GND
  41  GL2  OUT  = NC_PVDDCR_CPU1_P0_GL2_2

PU3  MPQ8633BGLEC838Z  MPQ8633BGLE-C838-Z IC  pkg QFN14_4X3  page 226
  1  BST  IN  = SW_PVDD18_S5_P1_BST
  2  AGND  POWER  = GND
  3  CS  IN  = PVDD18_S5_P1_CS
  4  MODE  IN  = PVDD18_S5_P1_MODE
  5  TRK_REF  IN  = PVDD18_S5_P1_REF
  6  RGND  POWER  = PVDD18_SS_P1_RGND
  7  FB  IN  = PVDD18_S5_P1_FB
  8  EN  IN  = PVDD18_S5_P1_EN
  9  PGOOD  OUT  = PWRGD_PVDD18_S5_P1
  10  VIN1  IN  = SW_P12V_AUX_PVDD18_S5_P1_FLT
  11_18  PGND  POWER  = GND
  19  VCC  IN  = PVDD18_S5_P1_VCC
  20  SW  OUT  = SW_PVDD18_S5_P1_SW
  21  VIN2  IN  = SW_P12V_AUX_PVDD18_S5_P1_FLT

PU4  ISL99390FRZTR5935  ISL99390FRZ-TR5935 IC  pkg QFN21_6X5XB  page 211
  1  VOS  IN  = PVDDCR_CPU0_P1_VOS1
  2  AGND  POWER  = GND
  3  VCC  POWER  = PVDDCR_CPU0_P1_VCC1
  4  PVCC  POWER  = PVDDCR_CPU0_P1_PVCC
  5  PGND1  POWER  = GND
  6  GL1  OUT  = NC_PVDDCR_CPU0_P1_GL1_1
  7_9-20_24  PGND2  POWER  = GND
  10_19  SW  OUT  = SW_PVDDCR_CPU0_P1_SW1
  25_29  VIN1  IN  = SW_P12V_AUX_PVDDCR_CPU0_P1_FLT
  30  VIN2  IN  = SW_P12V_AUX_PVDDCR_CPU0_P1_FLT
  31  DNC  TRI  = NC_PVDDCR_CPU0_P1_DNC1
  32  PHASE  POWER  = SW_PVDDCR_CPU0_P1_PH1
  33  BOOT  POWER  = SW_PVDDCR_CPU0_P1_BOOT1
  34  PWM  IN  = PVDDCR_CPU0_P1_PWM1
  35  EN  IN  = PVDDCR_CPU0_P1_VCC1
  36  TOUT_FLT  OUT  = PVDDCR_CPU0_P1_TEMP0
  37  LSET  OUT  = PVDDCR_CPU0_P1_LSET1
  38  IOUT  OUT  = PVDDCR_CPU0_P1_IMON1
  39  REFIN  IN  = PVDDCR_CPU0_P1_VCCS
  40  PGND3  POWER  = GND
  41  GL2  OUT  = NC_PVDDCR_CPU0_P1_GL2_1

PU5  ISL99390FRZTR5935  ISL99390FRZ-TR5935 IC  pkg QFN21_6X5XB  page 218
  1  VOS  IN  = PVDDCR_CPU1_P1_VOS2
  2  AGND  POWER  = GND
  3  VCC  POWER  = PVDDCR_CPU1_P1_VCC2
  4  PVCC  POWER  = PVDDCR_CPU1_P1_PVCC
  5  PGND1  POWER  = GND
  6  GL1  OUT  = NC_PVDDCR_CPU1_P1_GL1_2
  7_9-20_24  PGND2  POWER  = GND
  10_19  SW  OUT  = SW_PVDDCR_CPU1_P1_SW2
  25_29  VIN1  IN  = SW_P12V_AUX_PVDDCR_CPU1_P1_FLT
  30  VIN2  IN  = SW_P12V_AUX_PVDDCR_CPU1_P1_FLT
  31  DNC  TRI  = NC_PVDDCR_CPU1_P1_DNC2
  32  PHASE  POWER  = SW_PVDDCR_CPU1_P1_BOOTR2
  33  BOOT  POWER  = SW_PVDDCR_CPU1_P1_BOOT2
  34  PWM  IN  = PVDDCR_CPU1_P1_PWM2
  35  EN  IN  = PVDDCR_CPU1_P1_VCC2
  36  TOUT_FLT  OUT  = PVDDCR_CPU1_P1_TEMP0
  37  LSET  OUT  = PVDDCR_CPU1_P1_LSET2
  38  IOUT  OUT  = PVDDCR_CPU1_P1_IMON2
  39  REFIN  IN  = PVDDCR_CPU1_P1_VCCS
  40  PGND3  POWER  = GND
  41  GL2  OUT  = NC_PVDDCR_CPU1_P1_GL2_2

PU6  ISL99390FRZTR5935  ISL99390FRZ-TR5935 IC  pkg QFN21_6X5XB  page 194
  1  VOS  IN  = PVDDCR_CPU0_P0_VOS1
  2  AGND  POWER  = GND
  3  VCC  POWER  = PVDDCR_CPU0_P0_VCC1
  4  PVCC  POWER  = PVDDCR_CPU0_P0_PVCC
  5  PGND1  POWER  = GND
  6  GL1  OUT  = NC_PVDDCR_CPU0_P0_GL1_1
  7_9-20_24  PGND2  POWER  = GND
  10_19  SW  OUT  = SW_PVDDCR_CPU0_P0_SW1
  25_29  VIN1  IN  = SW_P12V_AUX_PVDDCR_CPU0_P0_FLT
  30  VIN2  IN  = SW_P12V_AUX_PVDDCR_CPU0_P0_FLT
  31  DNC  TRI  = NC_PVDDCR_CPU0_P0_DNC1
  32  PHASE  POWER  = SW_PVDDCR_CPU0_P0_PH1
  33  BOOT  POWER  = SW_PVDDCR_CPU0_P0_BOOT1
  34  PWM  IN  = PVDDCR_CPU0_P0_PWM1
  35  EN  IN  = PVDDCR_CPU0_P0_VCC1
  36  TOUT_FLT  OUT  = PVDDCR_CPU0_P0_TEMP0
  37  LSET  OUT  = PVDDCR_CPU0_P0_LSET1
  38  IOUT  OUT  = PVDDCR_CPU0_P0_IMON1
  39  REFIN  IN  = PVDDCR_CPU0_P0_VCCS
  40  PGND3  POWER  = GND
  41  GL2  OUT  = NC_PVDDCR_CPU0_P0_GL2_1

PU9  NCP3284AMNTXG  IC  pkg PQFN22_6X5  page 190
  1  ILIM  OUT  = P3V3_AUX_ILIM
  2  PGOOD  OUT  = PWRGD_P3V3_AUX_R1
  3  VIN  POWER  = P12V_AUX
  4  VCC  POWER  = P3V3_AUX_VCC
  5  VDRV  POWER  = P3V3_AUX_VDRV
  6  GL1  OUT  = NC_PU9_3
  7_10-19  PGND  POWER  = GND
  11_18  SW  BI  = SW_P3V3_AUX_SW
  20_24  PVIN  POWER  = SW_P3V3_AUX_FLT
  25  PHASE  IN  = SW_P3V3_AUX_BOOTR
  26  BOOT  BI  = SW_P3V3_AUX_BOOT
  27  EN  IN  = P3V3_AUX_EN
  28  VOS  IN  = P3V3_AUX_VOS
  29  SS  IN  = P3V3_AUX_SS
  30  FB  IN  = P3V3_AUX_FB
  31  \vsns-\  IN  = GND
  32  AGND  POWER  = GND
  33  NC1  TRI  = NC_PU9_1
  34  NC2  TRI  = NC_PU9_2
  35  \hiccup#\  IN  = NC_HICCUP
  36  \mode||fset\  IN  = P3V3_AUX_MODE
  37  GL2  OUT  = NC_PU9_4

PU10  ISL99390FRZTR5935  ISL99390FRZ-TR5935 IC  pkg QFN21_6X5XB  page 196
  1  VOS  IN  = PVDDCR_CPU0_P0_VOS6
  2  AGND  POWER  = GND
  3  VCC  POWER  = PVDDCR_CPU0_P0_VCC6
  4  PVCC  POWER  = PVDDCR_CPU0_P0_PVCC
  5  PGND1  POWER  = GND
  6  GL1  OUT  = NC_PVDDCR_CPU0_P0_GL1_6
  7_9-20_24  PGND2  POWER  = GND
  10_19  SW  OUT  = SW_PVDDCR_CPU0_P0_SW6
  25_29  VIN1  IN  = SW_P12V_AUX_PVDDCR_CPU0_P0_FLT
  30  VIN2  IN  = SW_P12V_AUX_PVDDCR_CPU0_P0_FLT
  31  DNC  TRI  = NC_PVDDCR_CPU0_P0_DNC6
  32  PHASE  POWER  = SW_PVDDCR_CPU0_P0_PH6
  33  BOOT  POWER  = SW_PVDDCR_CPU0_P0_BOOT6
  34  PWM  IN  = PVDDCR_CPU0_P0_PWM6
  35  EN  IN  = PVDDCR_CPU0_P0_VCC6
  36  TOUT_FLT  OUT  = PVDDCR_CPU0_P0_TEMP0
  37  LSET  OUT  = PVDDCR_CPU0_P0_LSET6
  38  IOUT  OUT  = PVDDCR_CPU0_P0_IMON6
  39  REFIN  IN  = PVDDCR_CPU0_P0_VCCS
  40  PGND3  POWER  = GND
  41  GL2  OUT  = NC_PVDDCR_CPU0_P0_GL2_6

PU11  ISL99390FRZTR5935  ISL99390FRZ-TR5935 IC  pkg QFN21_6X5XB  page 203
  1  VOS  IN  = PVDDCR_CPU1_P0_VOS6
  2  AGND  POWER  = GND
  3  VCC  POWER  = PVDDCR_CPU1_P0_VCC6
  4  PVCC  POWER  = PVDDCR_CPU1_P0_PVCC
  5  PGND1  POWER  = GND
  6  GL1  OUT  = NC_PVDDCR_CPU1_P0_GL1_6
  7_9-20_24  PGND2  POWER  = GND
  10_19  SW  OUT  = SW_PVDDCR_CPU1_P0_SW6
  25_29  VIN1  IN  = SW_P12V_AUX_PVDDCR_CPU1_P0_FLT
  30  VIN2  IN  = SW_P12V_AUX_PVDDCR_CPU1_P0_FLT
  31  DNC  TRI  = NC_PVDDCR_CPU1_P0_DNC6
  32  PHASE  POWER  = SW_PVDDCR_CPU1_P0_BOOTR6
  33  BOOT  POWER  = SW_PVDDCR_CPU1_P0_BOOT6
  34  PWM  IN  = PVDDCR_CPU1_P0_PWM6
  35  EN  IN  = PVDDCR_CPU1_P0_VCC6
  36  TOUT_FLT  OUT  = PVDDCR_CPU1_P0_TEMP0
  37  LSET  OUT  = PVDDCR_CPU1_P0_LSET6
  38  IOUT  OUT  = PVDDCR_CPU1_P0_IMON6
  39  REFIN  IN  = PVDDCR_CPU1_P0_VCCS
  40  PGND3  POWER  = GND
  41  GL2  OUT  = NC_PVDDCR_CPU1_P0_GL2_6

PU12  RAA229620GNPHA0  RAA229620GNP#HA0 IC  pkg QFN48_TH_0-4_6X6XH  page 200
  1  PWM0  OUT  = PVDDIO_P0_PWM1
  2  PWM1  OUT  = PVDDIO_P0_PWM2
  3  PWM2  OUT  = PVDDIO_P0_PWM3
  4  PWM3  OUT  = PVDDIO_P0_PWM4
  5  PWM4  OUT  = NC_PVDDCR_CPU1_P0_PWM8
  6  PWM5  OUT  = NC_PVDDCR_CPU1_P0_PWM7
  7  PWM6  OUT  = PVDDCR_CPU1_P0_PWM6
  8  PWM7  OUT  = PVDDCR_CPU1_P0_PWM5
  9  PWM8  OUT  = PVDDCR_CPU1_P0_PWM4
  10  PWM9  OUT  = PVDDCR_CPU1_P0_PWM3
  11  PWM10  OUT  = PVDDCR_CPU1_P0_PWM2
  12  PWM11  OUT  = PVDDCR_CPU1_P0_PWM1
  13  PMSDA  BI  = SMB_DIO_PVDDCR_CPU1_P0_R
  14  PMSCL  IN  = SMB_CLK_PVDDCR_CPU1_P0_R
  15  NPMALERT  OUT  = PVDDCR_CPU1_P0_SMB_ALERT_R
  16  PG0  OUT  = PWRGD_PVDDCR_CPU1_P0_R
  17  EN0  IN  = PVDDCR_CPU1_P0_EN_R
  18  RESET_L  IN  = PVDDCR_CPU1_P0_RESET_N_R
  19  VDDIO  POWER  = PVDD18_S5_P0
  20  PG1  OUT  = PWRGD_PVDDIO_P0_R
  21  SVD  IN  = SVID_PVDDCR_CPU1_P0_SVD_R1
  22  SVC  IN  = SVID_PVDDCR_CPU1_P0_SVC_R1
  23  SVTO  OUT  = SVID_PVDDCR_CPU1_P0_SVTO_R
  24  SVTI  IN  = SVID_PVDDCR_CPU1_P0_SVTI_R
  25  VSEN0  IN  = VSENSE_PVDDCR_CPU1_P0_VSEN0
  26  RGND0  IN  = VSENSE_VSS_SENSE_C_P0
  27  CS11  IN  = PVDDCR_CPU1_P0_IMON1
  28  CS10  IN  = PVDDCR_CPU1_P0_IMON2
  29  CS9  IN  = PVDDCR_CPU1_P0_IMON3
  30  CS8  IN  = PVDDCR_CPU1_P0_IMON4
  31  CS7  IN  = PVDDCR_CPU1_P0_IMON5
  32  CS6  IN  = PVDDCR_CPU1_P0_IMON6
  33  CS5  IN  = NC_PVDDCR_CPU1_P0_IMON7
  34  CS4  IN  = NC_PVDDCR_CPU1_P0_IMON8
  35  CS3  IN  = PVDDIO_P0_IMON4
  36  CS2  IN  = PVDDIO_P0_IMON3
  37  CS1  IN  = PVDDIO_P0_IMON2
  38  CS0  IN  = PVDDIO_P0_IMON1
  39  RGND1  IN  = VSENSE_VSS_SENSE_B_P0
  40  VSEN1  IN  = VSENSE_PVDDIO_P0_VSEN1
  41  OCP_L  OUT  = PVDDCR_CPU1_P0_OCP_N_R
  42  \en1||addr_cfg\  IN  = PVDDCR_CPU1_P0_EN1_ADDR_CFG
  43  TEMP1  IN  = PVDDIO_P0_TEMP1
  44  TEMP0  IN  = PVDDCR_CPU1_P0_TEMP0
  45  \vmon||iinsen\  BI  = PVDDCR_CPU1_P0_VMON
  46  VINSEN  IN  = PVDDCR_CPU1_P0_VINSEN
  47  VCC  POWER  = PVDDCR_CPU1_P0_VCC
  48  VCCS  POWER  = PVDDCR_CPU1_P0_VCCS
  TH  TH_GND  POWER  = GND

PU13  ISL99390FRZTR5935  ISL99390FRZ-TR5935 IC  pkg QFN21_6X5XB  page 201
  1  VOS  IN  = PVDDCR_CPU1_P0_VOS1
  2  AGND  POWER  = GND
  3  VCC  POWER  = PVDDCR_CPU1_P0_VCC1
  4  PVCC  POWER  = PVDDCR_CPU1_P0_PVCC
  5  PGND1  POWER  = GND
  6  GL1  OUT  = NC_PVDDCR_CPU1_P0_GL1_1
  7_9-20_24  PGND2  POWER  = GND
  10_19  SW  OUT  = SW_PVDDCR_CPU1_P0_SW1
  25_29  VIN1  IN  = SW_P12V_AUX_PVDDCR_CPU1_P0_FLT
  30  VIN2  IN  = SW_P12V_AUX_PVDDCR_CPU1_P0_FLT
  31  DNC  TRI  = NC_PVDDCR_CPU1_P0_DNC1
  32  PHASE  POWER  = SW_PVDDCR_CPU1_P0_BOOTR1
  33  BOOT  POWER  = SW_PVDDCR_CPU1_P0_BOOT1
  34  PWM  IN  = PVDDCR_CPU1_P0_PWM1
  35  EN  IN  = PVDDCR_CPU1_P0_VCC1
  36  TOUT_FLT  OUT  = PVDDCR_CPU1_P0_TEMP0
  37  LSET  OUT  = PVDDCR_CPU1_P0_LSET1
  38  IOUT  OUT  = PVDDCR_CPU1_P0_IMON1
  39  REFIN  IN  = PVDDCR_CPU1_P0_VCCS
  40  PGND3  POWER  = GND
  41  GL2  OUT  = NC_PVDDCR_CPU1_P0_GL2_1
